(kicad_pcb
	(version 20260206)
	(generator "pcbnew")
	(generator_version "10.0")
	(general
		(thickness 1.6)
		(legacy_teardrops no)
	)
	(paper "A4")
	(title_block
		(title "03242023_DA0F0TMBIJ0_F0T_Motherboard_J_brd_V01_OCP.brd")
		(comment 1 "Grand Teton / footprints 3361-3366 of 6105")
	)
	(layers
		(0 "F.Cu" signal "TOP")
		(4 "In1.Cu" signal "GND")
		(6 "In2.Cu" signal "IN1")
		(8 "In3.Cu" signal "GND1")
		(10 "In4.Cu" signal "IN2")
		(12 "In5.Cu" signal "GND2")
		(14 "In6.Cu" signal "IN3")
		(16 "In7.Cu" signal "GND3")
		(18 "In8.Cu" signal "VCC")
		(20 "In9.Cu" signal "VCC1")
		(22 "In10.Cu" signal "GND4")
		(24 "In11.Cu" signal "IN4")
		(26 "In12.Cu" signal "GND5")
		(28 "In13.Cu" signal "IN5")
		(30 "In14.Cu" signal "GND6")
		(32 "In15.Cu" signal "IN6")
		(34 "In16.Cu" signal "GND7")
		(2 "B.Cu" signal "BOTTOM")
		(9 "F.Adhes" user "F.Adhesive")
		(11 "B.Adhes" user "B.Adhesive")
		(13 "F.Paste" user "Package Geometry/Pastemask Top")
		(15 "B.Paste" user "Package Geometry/Pastemask Bottom")
		(5 "F.SilkS" user "Ref Des/Silkscreen Top")
		(7 "B.SilkS" user "Ref Des/Silkscreen Bottom")
		(1 "F.Mask" user "Board Geometry/Soldermask Top")
		(3 "B.Mask" user "Board Geometry/Soldermask Bottom")
		(17 "Dwgs.User" user "User.Drawings")
		(19 "Cmts.User" user "User.Comments")
		(21 "Eco1.User" user "User.Eco1")
		(23 "Eco2.User" user "User.Eco2")
		(25 "Edge.Cuts" user "Board Geometry/Outline")
		(27 "Margin" user)
		(31 "F.CrtYd" user "Package Geometry/Place Bound Top")
		(29 "B.CrtYd" user "Package Geometry/Place Bound Bottom")
		(35 "F.Fab" user "Ref Des/Assembly Top")
		(33 "B.Fab" user "Ref Des/Assembly Bottom")
	)
	(footprint ""
		(layer "F.Cu")
		(at 189.65037 -426.303948 180)
		(property "Reference" "R3907"
			(at 0 0 180)
			(layer "F.SilkS")
			(hide yes)
			(effects
				(font
					(size 1.27 1.27)
				)
			)
		)
		(property "Value" ""
			(at 0 0 180)
			(layer "F.Fab")
			(effects
				(font
					(size 1.27 1.27)
				)
			)
		)
		(duplicate_pad_numbers_are_jumpers no)
		(fp_line
			(start 0.7874 0.4064)
			(end -0.7874 0.4064)
			(stroke
				(width 0.1524)
				(type default)
			)
			(layer "F.SilkS")
		)
		(fp_line
			(start 0.7874 -0.4064)
			(end 0.7874 0.4064)
			(stroke
				(width 0.1524)
				(type default)
			)
			(layer "F.SilkS")
		)
		(fp_line
			(start -0.7874 0.4064)
			(end -0.7874 -0.4064)
			(stroke
				(width 0.1524)
				(type default)
			)
			(layer "F.SilkS")
		)
		(fp_line
			(start -0.7874 -0.4064)
			(end 0.7874 -0.4064)
			(stroke
				(width 0.1524)
				(type default)
			)
			(layer "F.SilkS")
		)
		(fp_line
			(start 0.67945 0.3048)
			(end 0.120396 0.3048)
			(stroke
				(width 0.1)
				(type default)
			)
			(layer "F.Fab")
		)
		(fp_line
			(start 0.67945 -0.3048)
			(end 0.67945 0.3048)
			(stroke
				(width 0.1)
				(type default)
			)
			(layer "F.Fab")
		)
		(fp_line
			(start 0.12065 -0.2794)
			(end 0.12065 -0.3048)
			(stroke
				(width 0.1)
				(type default)
			)
			(layer "F.Fab")
		)
		(fp_line
			(start 0.12065 -0.3048)
			(end 0.67945 -0.3048)
			(stroke
				(width 0.1)
				(type default)
			)
			(layer "F.Fab")
		)
		(fp_line
			(start 0.120396 0.3048)
			(end 0.120396 0.2794)
			(stroke
				(width 0.1)
				(type default)
			)
			(layer "F.Fab")
		)
		(fp_line
			(start 0.120396 0.2794)
			(end -0.12065 0.2794)
			(stroke
				(width 0.1)
				(type default)
			)
			(layer "F.Fab")
		)
		(fp_line
			(start -0.12065 0.3048)
			(end -0.67945 0.3048)
			(stroke
				(width 0.1)
				(type default)
			)
			(layer "F.Fab")
		)
		(fp_line
			(start -0.12065 0.2794)
			(end -0.12065 0.3048)
			(stroke
				(width 0.1)
				(type default)
			)
			(layer "F.Fab")
		)
		(fp_line
			(start -0.12065 -0.2794)
			(end 0.12065 -0.2794)
			(stroke
				(width 0.1)
				(type default)
			)
			(layer "F.Fab")
		)
		(fp_line
			(start -0.12065 -0.305054)
			(end -0.12065 -0.2794)
			(stroke
				(width 0.1)
				(type default)
			)
			(layer "F.Fab")
		)
		(fp_line
			(start -0.67945 0.3048)
			(end -0.67945 -0.305054)
			(stroke
				(width 0.1)
				(type default)
			)
			(layer "F.Fab")
		)
		(fp_line
			(start -0.67945 -0.305054)
			(end -0.12065 -0.305054)
			(stroke
				(width 0.1)
				(type default)
			)
			(layer "F.Fab")
		)
		(pad "1" smd circle
			(at -0.40005 0 180)
			(size 0 0)
			(layers "F.Cu" "F.Mask" "F.Paste")
			(net "PDB_PRSNT_N")
		)
		(pad "2" smd circle
			(at 0.40005 0 180)
			(size 0 0)
			(layers "F.Cu" "F.Mask" "F.Paste")
			(net "GND")
		)
	)
	(footprint ""
		(layer "F.Cu")
		(at 365.46663 -241.976656 -90)
		(property "Reference" "C1029"
			(at 0 0 270)
			(layer "F.SilkS")
			(hide yes)
			(effects
				(font
					(size 1.27 1.27)
				)
			)
		)
		(property "Value" ""
			(at 0 0 270)
			(layer "F.Fab")
			(effects
				(font
					(size 1.27 1.27)
				)
			)
		)
		(duplicate_pad_numbers_are_jumpers no)
		(fp_line
			(start -0.7874 0.4064)
			(end -0.7874 -0.4064)
			(stroke
				(width 0.1524)
				(type default)
			)
			(layer "F.SilkS")
		)
		(fp_line
			(start 0.7874 0.4064)
			(end -0.7874 0.4064)
			(stroke
				(width 0.1524)
				(type default)
			)
			(layer "F.SilkS")
		)
		(fp_line
			(start -0.7874 -0.4064)
			(end 0.7874 -0.4064)
			(stroke
				(width 0.1524)
				(type default)
			)
			(layer "F.SilkS")
		)
		(fp_line
			(start 0.7874 -0.4064)
			(end 0.7874 0.4064)
			(stroke
				(width 0.1524)
				(type default)
			)
			(layer "F.SilkS")
		)
		(fp_line
			(start -0.67945 0.3048)
			(end -0.67945 -0.305054)
			(stroke
				(width 0.1)
				(type default)
			)
			(layer "F.Fab")
		)
		(fp_line
			(start -0.12065 0.3048)
			(end -0.67945 0.3048)
			(stroke
				(width 0.1)
				(type default)
			)
			(layer "F.Fab")
		)
		(fp_line
			(start 0.120396 0.3048)
			(end 0.120396 0.2794)
			(stroke
				(width 0.1)
				(type default)
			)
			(layer "F.Fab")
		)
		(fp_line
			(start 0.67945 0.3048)
			(end 0.120396 0.3048)
			(stroke
				(width 0.1)
				(type default)
			)
			(layer "F.Fab")
		)
		(fp_line
			(start -0.12065 0.2794)
			(end -0.12065 0.3048)
			(stroke
				(width 0.1)
				(type default)
			)
			(layer "F.Fab")
		)
		(fp_line
			(start 0.120396 0.2794)
			(end -0.12065 0.2794)
			(stroke
				(width 0.1)
				(type default)
			)
			(layer "F.Fab")
		)
		(fp_line
			(start -0.12065 -0.2794)
			(end 0.12065 -0.2794)
			(stroke
				(width 0.1)
				(type default)
			)
			(layer "F.Fab")
		)
		(fp_line
			(start 0.12065 -0.2794)
			(end 0.12065 -0.3048)
			(stroke
				(width 0.1)
				(type default)
			)
			(layer "F.Fab")
		)
		(fp_line
			(start 0.12065 -0.3048)
			(end 0.67945 -0.3048)
			(stroke
				(width 0.1)
				(type default)
			)
			(layer "F.Fab")
		)
		(fp_line
			(start 0.67945 -0.3048)
			(end 0.67945 0.3048)
			(stroke
				(width 0.1)
				(type default)
			)
			(layer "F.Fab")
		)
		(fp_line
			(start -0.67945 -0.305054)
			(end -0.12065 -0.305054)
			(stroke
				(width 0.1)
				(type default)
			)
			(layer "F.Fab")
		)
		(fp_line
			(start -0.12065 -0.305054)
			(end -0.12065 -0.2794)
			(stroke
				(width 0.1)
				(type default)
			)
			(layer "F.Fab")
		)
		(pad "1" smd circle
			(at -0.40005 0 270)
			(size 0 0)
			(layers "F.Cu" "F.Mask" "F.Paste")
			(net "PVCCIN_CPU0")
		)
		(pad "2" smd circle
			(at 0.40005 0 270)
			(size 0 0)
			(layers "F.Cu" "F.Mask" "F.Paste")
			(net "GND")
		)
	)
	(footprint ""
		(layer "F.Cu")
		(at 181.15788 -99.659948 -90)
		(property "Reference" "R208"
			(at 0 0 270)
			(layer "F.SilkS")
			(hide yes)
			(effects
				(font
					(size 1.27 1.27)
				)
			)
		)
		(property "Value" ""
			(at 0 0 270)
			(layer "F.Fab")
			(effects
				(font
					(size 1.27 1.27)
				)
			)
		)
		(duplicate_pad_numbers_are_jumpers no)
		(fp_line
			(start -0.7874 0.4064)
			(end -0.7874 -0.4064)
			(stroke
				(width 0.1524)
				(type default)
			)
			(layer "F.SilkS")
		)
		(fp_line
			(start 0.7874 0.4064)
			(end -0.7874 0.4064)
			(stroke
				(width 0.1524)
				(type default)
			)
			(layer "F.SilkS")
		)
		(fp_line
			(start -0.7874 -0.4064)
			(end 0.7874 -0.4064)
			(stroke
				(width 0.1524)
				(type default)
			)
			(layer "F.SilkS")
		)
		(fp_line
			(start 0.7874 -0.4064)
			(end 0.7874 0.4064)
			(stroke
				(width 0.1524)
				(type default)
			)
			(layer "F.SilkS")
		)
		(fp_line
			(start -0.67945 0.3048)
			(end -0.67945 -0.305054)
			(stroke
				(width 0.1)
				(type default)
			)
			(layer "F.Fab")
		)
		(fp_line
			(start -0.12065 0.3048)
			(end -0.67945 0.3048)
			(stroke
				(width 0.1)
				(type default)
			)
			(layer "F.Fab")
		)
		(fp_line
			(start 0.120396 0.3048)
			(end 0.120396 0.2794)
			(stroke
				(width 0.1)
				(type default)
			)
			(layer "F.Fab")
		)
		(fp_line
			(start 0.67945 0.3048)
			(end 0.120396 0.3048)
			(stroke
				(width 0.1)
				(type default)
			)
			(layer "F.Fab")
		)
		(fp_line
			(start -0.12065 0.2794)
			(end -0.12065 0.3048)
			(stroke
				(width 0.1)
				(type default)
			)
			(layer "F.Fab")
		)
		(fp_line
			(start 0.120396 0.2794)
			(end -0.12065 0.2794)
			(stroke
				(width 0.1)
				(type default)
			)
			(layer "F.Fab")
		)
		(fp_line
			(start -0.12065 -0.2794)
			(end 0.12065 -0.2794)
			(stroke
				(width 0.1)
				(type default)
			)
			(layer "F.Fab")
		)
		(fp_line
			(start 0.12065 -0.2794)
			(end 0.12065 -0.3048)
			(stroke
				(width 0.1)
				(type default)
			)
			(layer "F.Fab")
		)
		(fp_line
			(start 0.12065 -0.3048)
			(end 0.67945 -0.3048)
			(stroke
				(width 0.1)
				(type default)
			)
			(layer "F.Fab")
		)
		(fp_line
			(start 0.67945 -0.3048)
			(end 0.67945 0.3048)
			(stroke
				(width 0.1)
				(type default)
			)
			(layer "F.Fab")
		)
		(fp_line
			(start -0.67945 -0.305054)
			(end -0.12065 -0.305054)
			(stroke
				(width 0.1)
				(type default)
			)
			(layer "F.Fab")
		)
		(fp_line
			(start -0.12065 -0.305054)
			(end -0.12065 -0.2794)
			(stroke
				(width 0.1)
				(type default)
			)
			(layer "F.Fab")
		)
		(pad "1" smd circle
			(at -0.40005 0 270)
			(size 0 0)
			(layers "F.Cu" "F.Mask" "F.Paste")
			(net "H_CPU0_MEMHOT_IN_LVC1_R_N")
		)
		(pad "2" smd circle
			(at 0.40005 0 270)
			(size 0 0)
			(layers "F.Cu" "F.Mask" "F.Paste")
			(net "H_CPU0_MEMHOT_IN_LVC1_R1_N")
		)
	)
	(footprint ""
		(layer "F.Cu")
		(at 322.095622 -59.299348)
		(property "Reference" "R456"
			(at 0 0 0)
			(layer "F.SilkS")
			(hide yes)
			(effects
				(font
					(size 1.27 1.27)
				)
			)
		)
		(property "Value" ""
			(at 0 0 0)
			(layer "F.Fab")
			(effects
				(font
					(size 1.27 1.27)
				)
			)
		)
		(duplicate_pad_numbers_are_jumpers no)
		(fp_line
			(start -0.7874 -0.4064)
			(end 0.7874 -0.4064)
			(stroke
				(width 0.1524)
				(type default)
			)
			(layer "F.SilkS")
		)
		(fp_line
			(start -0.7874 0.4064)
			(end -0.7874 -0.4064)
			(stroke
				(width 0.1524)
				(type default)
			)
			(layer "F.SilkS")
		)
		(fp_line
			(start 0.7874 -0.4064)
			(end 0.7874 0.4064)
			(stroke
				(width 0.1524)
				(type default)
			)
			(layer "F.SilkS")
		)
		(fp_line
			(start 0.7874 0.4064)
			(end -0.7874 0.4064)
			(stroke
				(width 0.1524)
				(type default)
			)
			(layer "F.SilkS")
		)
		(fp_line
			(start -0.67945 -0.305054)
			(end -0.12065 -0.305054)
			(stroke
				(width 0.1)
				(type default)
			)
			(layer "F.Fab")
		)
		(fp_line
			(start -0.67945 0.3048)
			(end -0.67945 -0.305054)
			(stroke
				(width 0.1)
				(type default)
			)
			(layer "F.Fab")
		)
		(fp_line
			(start -0.12065 -0.305054)
			(end -0.12065 -0.2794)
			(stroke
				(width 0.1)
				(type default)
			)
			(layer "F.Fab")
		)
		(fp_line
			(start -0.12065 -0.2794)
			(end 0.12065 -0.2794)
			(stroke
				(width 0.1)
				(type default)
			)
			(layer "F.Fab")
		)
		(fp_line
			(start -0.12065 0.2794)
			(end -0.12065 0.3048)
			(stroke
				(width 0.1)
				(type default)
			)
			(layer "F.Fab")
		)
		(fp_line
			(start -0.12065 0.3048)
			(end -0.67945 0.3048)
			(stroke
				(width 0.1)
				(type default)
			)
			(layer "F.Fab")
		)
		(fp_line
			(start 0.120396 0.2794)
			(end -0.12065 0.2794)
			(stroke
				(width 0.1)
				(type default)
			)
			(layer "F.Fab")
		)
		(fp_line
			(start 0.120396 0.3048)
			(end 0.120396 0.2794)
			(stroke
				(width 0.1)
				(type default)
			)
			(layer "F.Fab")
		)
		(fp_line
			(start 0.12065 -0.3048)
			(end 0.67945 -0.3048)
			(stroke
				(width 0.1)
				(type default)
			)
			(layer "F.Fab")
		)
		(fp_line
			(start 0.12065 -0.2794)
			(end 0.12065 -0.3048)
			(stroke
				(width 0.1)
				(type default)
			)
			(layer "F.Fab")
		)
		(fp_line
			(start 0.67945 -0.3048)
			(end 0.67945 0.3048)
			(stroke
				(width 0.1)
				(type default)
			)
			(layer "F.Fab")
		)
		(fp_line
			(start 0.67945 0.3048)
			(end 0.120396 0.3048)
			(stroke
				(width 0.1)
				(type default)
			)
			(layer "F.Fab")
		)
		(pad "1" smd circle
			(at -0.40005 0)
			(size 0 0)
			(layers "F.Cu" "F.Mask" "F.Paste")
			(net "P3V3_AUX")
		)
		(pad "2" smd circle
			(at 0.40005 0)
			(size 0 0)
			(layers "F.Cu" "F.Mask" "F.Paste")
			(net "PU_PCH_PMCALERT_N")
		)
	)
	(footprint ""
		(layer "F.Cu")
		(at 239.203738 -119.183658 -90)
		(property "Reference" "R3198"
			(at 0 0 270)
			(layer "F.SilkS")
			(hide yes)
			(effects
				(font
					(size 1.27 1.27)
				)
			)
		)
		(property "Value" ""
			(at 0 0 270)
			(layer "F.Fab")
			(effects
				(font
					(size 1.27 1.27)
				)
			)
		)
		(duplicate_pad_numbers_are_jumpers no)
		(fp_line
			(start -0.7874 0.4064)
			(end -0.7874 0.070358)
			(stroke
				(width 0.1524)
				(type default)
			)
			(layer "F.SilkS")
		)
		(fp_line
			(start 0.7874 0.4064)
			(end -0.7874 0.4064)
			(stroke
				(width 0.1524)
				(type default)
			)
			(layer "F.SilkS")
		)
		(fp_line
			(start 0.7874 0.022098)
			(end 0.7874 0.4064)
			(stroke
				(width 0.1524)
				(type default)
			)
			(layer "F.SilkS")
		)
		(fp_line
			(start -0.254762 -0.4064)
			(end 0.385318 -0.4064)
			(stroke
				(width 0.1524)
				(type default)
			)
			(layer "F.SilkS")
		)
		(fp_line
			(start -0.67945 0.3048)
			(end -0.67945 -0.305054)
			(stroke
				(width 0.1)
				(type default)
			)
			(layer "F.Fab")
		)
		(fp_line
			(start -0.12065 0.3048)
			(end -0.67945 0.3048)
			(stroke
				(width 0.1)
				(type default)
			)
			(layer "F.Fab")
		)
		(fp_line
			(start 0.120396 0.3048)
			(end 0.120396 0.2794)
			(stroke
				(width 0.1)
				(type default)
			)
			(layer "F.Fab")
		)
		(fp_line
			(start 0.67945 0.3048)
			(end 0.120396 0.3048)
			(stroke
				(width 0.1)
				(type default)
			)
			(layer "F.Fab")
		)
		(fp_line
			(start -0.12065 0.2794)
			(end -0.12065 0.3048)
			(stroke
				(width 0.1)
				(type default)
			)
			(layer "F.Fab")
		)
		(fp_line
			(start 0.120396 0.2794)
			(end -0.12065 0.2794)
			(stroke
				(width 0.1)
				(type default)
			)
			(layer "F.Fab")
		)
		(fp_line
			(start -0.12065 -0.2794)
			(end 0.12065 -0.2794)
			(stroke
				(width 0.1)
				(type default)
			)
			(layer "F.Fab")
		)
		(fp_line
			(start 0.12065 -0.2794)
			(end 0.12065 -0.3048)
			(stroke
				(width 0.1)
				(type default)
			)
			(layer "F.Fab")
		)
		(fp_line
			(start 0.12065 -0.3048)
			(end 0.67945 -0.3048)
			(stroke
				(width 0.1)
				(type default)
			)
			(layer "F.Fab")
		)
		(fp_line
			(start 0.67945 -0.3048)
			(end 0.67945 0.3048)
			(stroke
				(width 0.1)
				(type default)
			)
			(layer "F.Fab")
		)
		(fp_line
			(start -0.67945 -0.305054)
			(end -0.12065 -0.305054)
			(stroke
				(width 0.1)
				(type default)
			)
			(layer "F.Fab")
		)
		(fp_line
			(start -0.12065 -0.305054)
			(end -0.12065 -0.2794)
			(stroke
				(width 0.1)
				(type default)
			)
			(layer "F.Fab")
		)
		(pad "1" smd circle
			(at -0.40005 0 270)
			(size 0 0)
			(layers "F.Cu" "F.Mask" "F.Paste")
			(net "CLK_100M_OCP_V3_2_C_R_DP")
		)
		(pad "2" smd circle
			(at 0.40005 0 270)
			(size 0 0)
			(layers "F.Cu" "F.Mask" "F.Paste")
			(net "CLK_100M_OCP_V3_2_C_DP")
		)
	)
	(footprint ""
		(layer "F.Cu")
		(at 367.44783 -241.976656 -90)
		(property "Reference" "C1037"
			(at 0 0 270)
			(layer "F.SilkS")
			(hide yes)
			(effects
				(font
					(size 1.27 1.27)
				)
			)
		)
		(property "Value" ""
			(at 0 0 270)
			(layer "F.Fab")
			(effects
				(font
					(size 1.27 1.27)
				)
			)
		)
		(duplicate_pad_numbers_are_jumpers no)
		(fp_line
			(start -0.7874 0.4064)
			(end -0.7874 -0.4064)
			(stroke
				(width 0.1524)
				(type default)
			)
			(layer "F.SilkS")
		)
		(fp_line
			(start 0.7874 0.4064)
			(end -0.7874 0.4064)
			(stroke
				(width 0.1524)
				(type default)
			)
			(layer "F.SilkS")
		)
		(fp_line
			(start -0.7874 -0.4064)
			(end 0.7874 -0.4064)
			(stroke
				(width 0.1524)
				(type default)
			)
			(layer "F.SilkS")
		)
		(fp_line
			(start 0.7874 -0.4064)
			(end 0.7874 0.4064)
			(stroke
				(width 0.1524)
				(type default)
			)
			(layer "F.SilkS")
		)
		(fp_line
			(start -0.67945 0.3048)
			(end -0.67945 -0.305054)
			(stroke
				(width 0.1)
				(type default)
			)
			(layer "F.Fab")
		)
		(fp_line
			(start -0.12065 0.3048)
			(end -0.67945 0.3048)
			(stroke
				(width 0.1)
				(type default)
			)
			(layer "F.Fab")
		)
		(fp_line
			(start 0.120396 0.3048)
			(end 0.120396 0.2794)
			(stroke
				(width 0.1)
				(type default)
			)
			(layer "F.Fab")
		)
		(fp_line
			(start 0.67945 0.3048)
			(end 0.120396 0.3048)
			(stroke
				(width 0.1)
				(type default)
			)
			(layer "F.Fab")
		)
		(fp_line
			(start -0.12065 0.2794)
			(end -0.12065 0.3048)
			(stroke
				(width 0.1)
				(type default)
			)
			(layer "F.Fab")
		)
		(fp_line
			(start 0.120396 0.2794)
			(end -0.12065 0.2794)
			(stroke
				(width 0.1)
				(type default)
			)
			(layer "F.Fab")
		)
		(fp_line
			(start -0.12065 -0.2794)
			(end 0.12065 -0.2794)
			(stroke
				(width 0.1)
				(type default)
			)
			(layer "F.Fab")
		)
		(fp_line
			(start 0.12065 -0.2794)
			(end 0.12065 -0.3048)
			(stroke
				(width 0.1)
				(type default)
			)
			(layer "F.Fab")
		)
		(fp_line
			(start 0.12065 -0.3048)
			(end 0.67945 -0.3048)
			(stroke
				(width 0.1)
				(type default)
			)
			(layer "F.Fab")
		)
		(fp_line
			(start 0.67945 -0.3048)
			(end 0.67945 0.3048)
			(stroke
				(width 0.1)
				(type default)
			)
			(layer "F.Fab")
		)
		(fp_line
			(start -0.67945 -0.305054)
			(end -0.12065 -0.305054)
			(stroke
				(width 0.1)
				(type default)
			)
			(layer "F.Fab")
		)
		(fp_line
			(start -0.12065 -0.305054)
			(end -0.12065 -0.2794)
			(stroke
				(width 0.1)
				(type default)
			)
			(layer "F.Fab")
		)
		(pad "1" smd circle
			(at -0.40005 0 270)
			(size 0 0)
			(layers "F.Cu" "F.Mask" "F.Paste")
			(net "PVCCIN_CPU0")
		)
		(pad "2" smd circle
			(at 0.40005 0 270)
			(size 0 0)
			(layers "F.Cu" "F.Mask" "F.Paste")
			(net "GND")
		)
	)
)
